# S9S_MB_2U (Grand Teton) — schematic netlist excerpt (pin names and nets, part order shuffled) for the footprints in the layout excerpt that follows; sources: Cadence DE-HDL packaged netlist, KiCad conversion of 03242023_DA0F0TMBIJ0_F0T_Motherboard_J_brd_V01_OCP.brd

R2401  Q_RES  0 5% CHIP  pkg 0402LF  page 278 : A = SVID_ALERT1_CPU0_R_N ; B = SVID_ALERT_PVCCD_HV_CPU0_R
R4664  Q_RES  0 5% CHIP  pkg 0402LF  page 167 : A = P2E_MB_BMC_RX_DN<0> ; B = P2E_MB_BMC_RX_R1_DN<0>

(kicad_pcb
	(version 20260206)
	(generator "pcbnew")
	(generator_version "10.0")
	(general
		(thickness 1.6)
		(legacy_teardrops no)
	)
	(paper "A4")
	(title_block
		(title "03242023_DA0F0TMBIJ0_F0T_Motherboard_J_brd_V01_OCP.brd")
		(comment 1 "Grand Teton / footprints 341-342 of 6105")
	)
	(layers
		(0 "F.Cu" signal "TOP")
		(4 "In1.Cu" signal "GND")
		(6 "In2.Cu" signal "IN1")
		(8 "In3.Cu" signal "GND1")
		(10 "In4.Cu" signal "IN2")
		(12 "In5.Cu" signal "GND2")
		(14 "In6.Cu" signal "IN3")
		(16 "In7.Cu" signal "GND3")
		(18 "In8.Cu" signal "VCC")
		(20 "In9.Cu" signal "VCC1")
		(22 "In10.Cu" signal "GND4")
		(24 "In11.Cu" signal "IN4")
		(26 "In12.Cu" signal "GND5")
		(28 "In13.Cu" signal "IN5")
		(30 "In14.Cu" signal "GND6")
		(32 "In15.Cu" signal "IN6")
		(34 "In16.Cu" signal "GND7")
		(2 "B.Cu" signal "BOTTOM")
		(9 "F.Adhes" user "F.Adhesive")
		(11 "B.Adhes" user "B.Adhesive")
		(13 "F.Paste" user "Package Geometry/Pastemask Top")
		(15 "B.Paste" user "Package Geometry/Pastemask Bottom")
		(5 "F.SilkS" user "Ref Des/Silkscreen Top")
		(7 "B.SilkS" user "Ref Des/Silkscreen Bottom")
		(1 "F.Mask" user "Board Geometry/Soldermask Top")
		(3 "B.Mask" user "Board Geometry/Soldermask Bottom")
		(17 "Dwgs.User" user "User.Drawings")
		(19 "Cmts.User" user "User.Comments")
		(21 "Eco1.User" user "User.Eco1")
		(23 "Eco2.User" user "User.Eco2")
		(25 "Edge.Cuts" user "Board Geometry/Outline")
		(27 "Margin" user)
		(31 "F.CrtYd" user "Package Geometry/Place Bound Top")
		(29 "B.CrtYd" user "Package Geometry/Place Bound Bottom")
		(35 "F.Fab" user "Ref Des/Assembly Top")
		(33 "B.Fab" user "Ref Des/Assembly Bottom")
	)
	(footprint ""
		(layer "F.Cu")
		(at 437.242966 -125.696726 180)
		(property "Reference" "R2401"
			(at 0 0 180)
			(layer "F.SilkS")
			(hide yes)
			(effects
				(font
					(size 1.27 1.27)
				)
			)
		)
		(property "Value" ""
			(at 0 0 180)
			(layer "F.Fab")
			(effects
				(font
					(size 1.27 1.27)
				)
			)
		)
		(duplicate_pad_numbers_are_jumpers no)
		(fp_line
			(start 0.7874 0.4064)
			(end -0.7874 0.4064)
			(stroke
				(width 0.1524)
				(type default)
			)
			(layer "F.SilkS")
		)
		(fp_line
			(start 0.7874 -0.4064)
			(end 0.7874 0.4064)
			(stroke
				(width 0.1524)
				(type default)
			)
			(layer "F.SilkS")
		)
		(fp_line
			(start -0.7874 0.4064)
			(end -0.7874 -0.4064)
			(stroke
				(width 0.1524)
				(type default)
			)
			(layer "F.SilkS")
		)
		(fp_line
			(start -0.7874 -0.4064)
			(end 0.7874 -0.4064)
			(stroke
				(width 0.1524)
				(type default)
			)
			(layer "F.SilkS")
		)
		(fp_line
			(start 0.67945 0.3048)
			(end 0.120396 0.3048)
			(stroke
				(width 0.1)
				(type default)
			)
			(layer "F.Fab")
		)
		(fp_line
			(start 0.67945 -0.3048)
			(end 0.67945 0.3048)
			(stroke
				(width 0.1)
				(type default)
			)
			(layer "F.Fab")
		)
		(fp_line
			(start 0.12065 -0.2794)
			(end 0.12065 -0.3048)
			(stroke
				(width 0.1)
				(type default)
			)
			(layer "F.Fab")
		)
		(fp_line
			(start 0.12065 -0.3048)
			(end 0.67945 -0.3048)
			(stroke
				(width 0.1)
				(type default)
			)
			(layer "F.Fab")
		)
		(fp_line
			(start 0.120396 0.3048)
			(end 0.120396 0.2794)
			(stroke
				(width 0.1)
				(type default)
			)
			(layer "F.Fab")
		)
		(fp_line
			(start 0.120396 0.2794)
			(end -0.12065 0.2794)
			(stroke
				(width 0.1)
				(type default)
			)
			(layer "F.Fab")
		)
		(fp_line
			(start -0.12065 0.3048)
			(end -0.67945 0.3048)
			(stroke
				(width 0.1)
				(type default)
			)
			(layer "F.Fab")
		)
		(fp_line
			(start -0.12065 0.2794)
			(end -0.12065 0.3048)
			(stroke
				(width 0.1)
				(type default)
			)
			(layer "F.Fab")
		)
		(fp_line
			(start -0.12065 -0.2794)
			(end 0.12065 -0.2794)
			(stroke
				(width 0.1)
				(type default)
			)
			(layer "F.Fab")
		)
		(fp_line
			(start -0.12065 -0.305054)
			(end -0.12065 -0.2794)
			(stroke
				(width 0.1)
				(type default)
			)
			(layer "F.Fab")
		)
		(fp_line
			(start -0.67945 0.3048)
			(end -0.67945 -0.305054)
			(stroke
				(width 0.1)
				(type default)
			)
			(layer "F.Fab")
		)
		(fp_line
			(start -0.67945 -0.305054)
			(end -0.12065 -0.305054)
			(stroke
				(width 0.1)
				(type default)
			)
			(layer "F.Fab")
		)
		(pad "1" smd circle
			(at -0.40005 0 180)
			(size 0 0)
			(layers "F.Cu" "F.Mask" "F.Paste")
			(net "SVID_ALERT1_CPU0_R_N")
		)
		(pad "2" smd circle
			(at 0.40005 0 180)
			(size 0 0)
			(layers "F.Cu" "F.Mask" "F.Paste")
			(net "SVID_ALERT_PVCCD_HV_CPU0_R")
		)
	)
	(footprint ""
		(layer "F.Cu")
		(at 24.684482 -396.887192 -90)
		(property "Reference" "R4664"
			(at 0 0 270)
			(layer "F.SilkS")
			(hide yes)
			(effects
				(font
					(size 1.27 1.27)
				)
			)
		)
		(property "Value" ""
			(at 0 0 270)
			(layer "F.Fab")
			(effects
				(font
					(size 1.27 1.27)
				)
			)
		)
		(duplicate_pad_numbers_are_jumpers no)
		(fp_line
			(start -0.7874 0.4064)
			(end -0.7874 -0.4064)
			(stroke
				(width 0.1524)
				(type default)
			)
			(layer "F.SilkS")
		)
		(fp_line
			(start 0.7874 0.4064)
			(end -0.7874 0.4064)
			(stroke
				(width 0.1524)
				(type default)
			)
			(layer "F.SilkS")
		)
		(fp_line
			(start 0.017272 -0.4064)
			(end 0.7874 -0.4064)
			(stroke
				(width 0.1524)
				(type default)
			)
			(layer "F.SilkS")
		)
		(fp_line
			(start -0.67945 0.3048)
			(end -0.67945 -0.305054)
			(stroke
				(width 0.1)
				(type default)
			)
			(layer "F.Fab")
		)
		(fp_line
			(start -0.12065 0.3048)
			(end -0.67945 0.3048)
			(stroke
				(width 0.1)
				(type default)
			)
			(layer "F.Fab")
		)
		(fp_line
			(start 0.120396 0.3048)
			(end 0.120396 0.2794)
			(stroke
				(width 0.1)
				(type default)
			)
			(layer "F.Fab")
		)
		(fp_line
			(start 0.67945 0.3048)
			(end 0.120396 0.3048)
			(stroke
				(width 0.1)
				(type default)
			)
			(layer "F.Fab")
		)
		(fp_line
			(start -0.12065 0.2794)
			(end -0.12065 0.3048)
			(stroke
				(width 0.1)
				(type default)
			)
			(layer "F.Fab")
		)
		(fp_line
			(start 0.120396 0.2794)
			(end -0.12065 0.2794)
			(stroke
				(width 0.1)
				(type default)
			)
			(layer "F.Fab")
		)
		(fp_line
			(start -0.12065 -0.2794)
			(end 0.12065 -0.2794)
			(stroke
				(width 0.1)
				(type default)
			)
			(layer "F.Fab")
		)
		(fp_line
			(start 0.12065 -0.2794)
			(end 0.12065 -0.3048)
			(stroke
				(width 0.1)
				(type default)
			)
			(layer "F.Fab")
		)
		(fp_line
			(start 0.12065 -0.3048)
			(end 0.67945 -0.3048)
			(stroke
				(width 0.1)
				(type default)
			)
			(layer "F.Fab")
		)
		(fp_line
			(start 0.67945 -0.3048)
			(end 0.67945 0.3048)
			(stroke
				(width 0.1)
				(type default)
			)
			(layer "F.Fab")
		)
		(fp_line
			(start -0.67945 -0.305054)
			(end -0.12065 -0.305054)
			(stroke
				(width 0.1)
				(type default)
			)
			(layer "F.Fab")
		)
		(fp_line
			(start -0.12065 -0.305054)
			(end -0.12065 -0.2794)
			(stroke
				(width 0.1)
				(type default)
			)
			(layer "F.Fab")
		)
		(pad "1" smd rect
			(at -0.40005 0 90)
			(size 0.4572 0.508)
			(layers "F.Cu" "F.Mask" "F.Paste")
			(net "P2E_MB_BMC_RX_DN<0>")
		)
		(pad "2" smd rect
			(at 0.40005 0 90)
			(size 0.4572 0.508)
			(layers "F.Cu" "F.Mask" "F.Paste")
			(net "P2E_MB_BMC_RX_R1_DN<0>")
		)
	)
)
